(kicad_pcb
	(version 20260206)
	(generator "pcbnew")
	(generator_version "10.0")
	(general
		(thickness 1.6)
		(legacy_teardrops no)
	)
	(paper "A4")
	(title_block
		(title "01162023_DA0F0TEBIF0_F0T_Expander_BD_F_brd_V02_OCP.brd")
		(comment 1 "Grand Teton / footprints 5432-5438 of 9728")
	)
	(layers
		(0 "F.Cu" signal "TOP")
		(4 "In1.Cu" signal "GND")
		(6 "In2.Cu" signal "VCC")
		(8 "In3.Cu" signal "VCC1")
		(10 "In4.Cu" signal "GND1")
		(12 "In5.Cu" signal "IN1")
		(14 "In6.Cu" signal "GND2")
		(16 "In7.Cu" signal "IN2")
		(18 "In8.Cu" signal "GND3")
		(20 "In9.Cu" signal "IN3")
		(22 "In10.Cu" signal "GND4")
		(24 "In11.Cu" signal "IN4")
		(26 "In12.Cu" signal "GND5")
		(28 "In13.Cu" signal "IN5")
		(30 "In14.Cu" signal "GND6")
		(32 "In15.Cu" signal "IN6")
		(34 "In16.Cu" signal "GND7")
		(2 "B.Cu" signal "BOTTOM")
		(9 "F.Adhes" user "F.Adhesive")
		(11 "B.Adhes" user "B.Adhesive")
		(13 "F.Paste" user "Package Geometry/Pastemask Top")
		(15 "B.Paste" user "Package Geometry/Pastemask Bottom")
		(5 "F.SilkS" user "Ref Des/Silkscreen Top")
		(7 "B.SilkS" user "Ref Des/Silkscreen Bottom")
		(1 "F.Mask" user "Board Geometry/Soldermask Top")
		(3 "B.Mask" user "Board Geometry/Soldermask Bottom")
		(17 "Dwgs.User" user "User.Drawings")
		(19 "Cmts.User" user "User.Comments")
		(21 "Eco1.User" user "User.Eco1")
		(23 "Eco2.User" user "User.Eco2")
		(25 "Edge.Cuts" user "Board Geometry/Outline")
		(27 "Margin" user)
		(31 "F.CrtYd" user "Package Geometry/Place Bound Top")
		(29 "B.CrtYd" user "Package Geometry/Place Bound Bottom")
		(35 "F.Fab" user "Ref Des/Assembly Top")
		(33 "B.Fab" user "Ref Des/Assembly Bottom")
	)
	(footprint ""
		(layer "F.Cu")
		(at 249.733562 -210.606386)
		(property "Reference" "R4433"
			(at 0 0 0)
			(layer "F.SilkS")
			(hide yes)
			(effects
				(font
					(size 1.27 1.27)
				)
			)
		)
		(property "Value" ""
			(at 0 0 0)
			(layer "F.Fab")
			(effects
				(font
					(size 1.27 1.27)
				)
			)
		)
		(duplicate_pad_numbers_are_jumpers no)
		(fp_line
			(start -0.7874 -0.4064)
			(end 0.7874 -0.4064)
			(stroke
				(width 0.1524)
				(type default)
			)
			(layer "F.SilkS")
		)
		(fp_line
			(start -0.7874 0.4064)
			(end -0.7874 -0.4064)
			(stroke
				(width 0.1524)
				(type default)
			)
			(layer "F.SilkS")
		)
		(fp_line
			(start 0.7874 -0.4064)
			(end 0.7874 0.4064)
			(stroke
				(width 0.1524)
				(type default)
			)
			(layer "F.SilkS")
		)
		(fp_line
			(start 0.7874 0.4064)
			(end -0.7874 0.4064)
			(stroke
				(width 0.1524)
				(type default)
			)
			(layer "F.SilkS")
		)
		(fp_line
			(start -0.67945 -0.305054)
			(end -0.12065 -0.305054)
			(stroke
				(width 0.1)
				(type default)
			)
			(layer "F.Fab")
		)
		(fp_line
			(start -0.67945 0.3048)
			(end -0.67945 -0.305054)
			(stroke
				(width 0.1)
				(type default)
			)
			(layer "F.Fab")
		)
		(fp_line
			(start -0.12065 -0.305054)
			(end -0.12065 -0.2794)
			(stroke
				(width 0.1)
				(type default)
			)
			(layer "F.Fab")
		)
		(fp_line
			(start -0.12065 -0.2794)
			(end 0.12065 -0.2794)
			(stroke
				(width 0.1)
				(type default)
			)
			(layer "F.Fab")
		)
		(fp_line
			(start -0.12065 0.2794)
			(end -0.12065 0.3048)
			(stroke
				(width 0.1)
				(type default)
			)
			(layer "F.Fab")
		)
		(fp_line
			(start -0.12065 0.3048)
			(end -0.67945 0.3048)
			(stroke
				(width 0.1)
				(type default)
			)
			(layer "F.Fab")
		)
		(fp_line
			(start 0.120396 0.2794)
			(end -0.12065 0.2794)
			(stroke
				(width 0.1)
				(type default)
			)
			(layer "F.Fab")
		)
		(fp_line
			(start 0.120396 0.3048)
			(end 0.120396 0.2794)
			(stroke
				(width 0.1)
				(type default)
			)
			(layer "F.Fab")
		)
		(fp_line
			(start 0.12065 -0.3048)
			(end 0.67945 -0.3048)
			(stroke
				(width 0.1)
				(type default)
			)
			(layer "F.Fab")
		)
		(fp_line
			(start 0.12065 -0.2794)
			(end 0.12065 -0.3048)
			(stroke
				(width 0.1)
				(type default)
			)
			(layer "F.Fab")
		)
		(fp_line
			(start 0.67945 -0.3048)
			(end 0.67945 0.3048)
			(stroke
				(width 0.1)
				(type default)
			)
			(layer "F.Fab")
		)
		(fp_line
			(start 0.67945 0.3048)
			(end 0.120396 0.3048)
			(stroke
				(width 0.1)
				(type default)
			)
			(layer "F.Fab")
		)
		(pad "1" smd circle
			(at -0.40005 0)
			(size 0 0)
			(layers "F.Cu" "F.Mask" "F.Paste")
			(net "P3V3_AUX")
		)
		(pad "2" smd circle
			(at 0.40005 0)
			(size 0 0)
			(layers "F.Cu" "F.Mask" "F.Paste")
			(net "PWRGD_P1V2_AUX")
		)
	)
	(footprint ""
		(layer "F.Cu")
		(at 480.78009 -547.47541 180)
		(property "Reference" "SCREW_SSD15_1"
			(at -5.6007 -1.402334 0)
			(unlocked yes)
			(layer "B.SilkS")
			(effects
				(font
					(size 0.7874 0.5842)
					(thickness 0.1524)
				)
				(justify mirror)
			)
		)
		(property "Value" ""
			(at 0 0 180)
			(layer "F.Fab")
			(effects
				(font
					(size 1.27 1.27)
				)
			)
		)
		(duplicate_pad_numbers_are_jumpers no)
		(pad "1" thru_hole circle
			(at 0 0 180)
			(size 0.4572 0.4572)
			(drill 0.2032)
			(layers "*.Cu" "*.Mask")
			(remove_unused_layers no)
			(net "Net_9144")
			(clearance 0.127)
			(thermal_gap 0.127)
			(padstack
				(mode front_inner_back)
				(layer "Inner"
					(shape circle)
					(size 0.4572 0.4572)
					(clearance 0.127)
				)
				(layer "B.Cu"
					(shape circle)
					(size 0.508 0.508)
					(clearance 0.1016)
				)
			)
		)
	)
	(footprint ""
		(layer "F.Cu")
		(at 315.493908 -34.248852)
		(property "Reference" "R5688"
			(at 0 0 0)
			(layer "F.SilkS")
			(hide yes)
			(effects
				(font
					(size 1.27 1.27)
				)
			)
		)
		(property "Value" ""
			(at 0 0 0)
			(layer "F.Fab")
			(effects
				(font
					(size 1.27 1.27)
				)
			)
		)
		(duplicate_pad_numbers_are_jumpers no)
		(fp_line
			(start -0.7874 -0.4064)
			(end 0.7874 -0.4064)
			(stroke
				(width 0.1524)
				(type default)
			)
			(layer "F.SilkS")
		)
		(fp_line
			(start -0.7874 0.4064)
			(end -0.7874 -0.4064)
			(stroke
				(width 0.1524)
				(type default)
			)
			(layer "F.SilkS")
		)
		(fp_line
			(start 0.7874 -0.4064)
			(end 0.7874 0.4064)
			(stroke
				(width 0.1524)
				(type default)
			)
			(layer "F.SilkS")
		)
		(fp_line
			(start 0.7874 0.4064)
			(end -0.7874 0.4064)
			(stroke
				(width 0.1524)
				(type default)
			)
			(layer "F.SilkS")
		)
		(fp_line
			(start -0.67945 -0.305054)
			(end -0.12065 -0.305054)
			(stroke
				(width 0.1)
				(type default)
			)
			(layer "F.Fab")
		)
		(fp_line
			(start -0.67945 0.3048)
			(end -0.67945 -0.305054)
			(stroke
				(width 0.1)
				(type default)
			)
			(layer "F.Fab")
		)
		(fp_line
			(start -0.12065 -0.305054)
			(end -0.12065 -0.2794)
			(stroke
				(width 0.1)
				(type default)
			)
			(layer "F.Fab")
		)
		(fp_line
			(start -0.12065 -0.2794)
			(end 0.12065 -0.2794)
			(stroke
				(width 0.1)
				(type default)
			)
			(layer "F.Fab")
		)
		(fp_line
			(start -0.12065 0.2794)
			(end -0.12065 0.3048)
			(stroke
				(width 0.1)
				(type default)
			)
			(layer "F.Fab")
		)
		(fp_line
			(start -0.12065 0.3048)
			(end -0.67945 0.3048)
			(stroke
				(width 0.1)
				(type default)
			)
			(layer "F.Fab")
		)
		(fp_line
			(start 0.120396 0.2794)
			(end -0.12065 0.2794)
			(stroke
				(width 0.1)
				(type default)
			)
			(layer "F.Fab")
		)
		(fp_line
			(start 0.120396 0.3048)
			(end 0.120396 0.2794)
			(stroke
				(width 0.1)
				(type default)
			)
			(layer "F.Fab")
		)
		(fp_line
			(start 0.12065 -0.3048)
			(end 0.67945 -0.3048)
			(stroke
				(width 0.1)
				(type default)
			)
			(layer "F.Fab")
		)
		(fp_line
			(start 0.12065 -0.2794)
			(end 0.12065 -0.3048)
			(stroke
				(width 0.1)
				(type default)
			)
			(layer "F.Fab")
		)
		(fp_line
			(start 0.67945 -0.3048)
			(end 0.67945 0.3048)
			(stroke
				(width 0.1)
				(type default)
			)
			(layer "F.Fab")
		)
		(fp_line
			(start 0.67945 0.3048)
			(end 0.120396 0.3048)
			(stroke
				(width 0.1)
				(type default)
			)
			(layer "F.Fab")
		)
		(pad "1" smd circle
			(at -0.40005 0)
			(size 0 0)
			(layers "F.Cu" "F.Mask" "F.Paste")
			(net "RST_SMB_SSD11_ISO_N")
		)
		(pad "2" smd circle
			(at 0.40005 0)
			(size 0 0)
			(layers "F.Cu" "F.Mask" "F.Paste")
			(net "P3V3_SSD11")
		)
	)
	(footprint ""
		(layer "F.Cu")
		(at 281.867864 -19.453098)
		(property "Reference" "R1696"
			(at 0 0 0)
			(layer "F.SilkS")
			(hide yes)
			(effects
				(font
					(size 1.27 1.27)
				)
			)
		)
		(property "Value" ""
			(at 0 0 0)
			(layer "F.Fab")
			(effects
				(font
					(size 1.27 1.27)
				)
			)
		)
		(duplicate_pad_numbers_are_jumpers no)
		(fp_line
			(start -0.7874 -0.4064)
			(end 0.7874 -0.4064)
			(stroke
				(width 0.1524)
				(type default)
			)
			(layer "F.SilkS")
		)
		(fp_line
			(start -0.7874 0.4064)
			(end -0.7874 -0.4064)
			(stroke
				(width 0.1524)
				(type default)
			)
			(layer "F.SilkS")
		)
		(fp_line
			(start 0.7874 -0.4064)
			(end 0.7874 0.4064)
			(stroke
				(width 0.1524)
				(type default)
			)
			(layer "F.SilkS")
		)
		(fp_line
			(start 0.7874 0.4064)
			(end -0.7874 0.4064)
			(stroke
				(width 0.1524)
				(type default)
			)
			(layer "F.SilkS")
		)
		(fp_line
			(start -0.67945 -0.305054)
			(end -0.12065 -0.305054)
			(stroke
				(width 0.1)
				(type default)
			)
			(layer "F.Fab")
		)
		(fp_line
			(start -0.67945 0.3048)
			(end -0.67945 -0.305054)
			(stroke
				(width 0.1)
				(type default)
			)
			(layer "F.Fab")
		)
		(fp_line
			(start -0.12065 -0.305054)
			(end -0.12065 -0.2794)
			(stroke
				(width 0.1)
				(type default)
			)
			(layer "F.Fab")
		)
		(fp_line
			(start -0.12065 -0.2794)
			(end 0.12065 -0.2794)
			(stroke
				(width 0.1)
				(type default)
			)
			(layer "F.Fab")
		)
		(fp_line
			(start -0.12065 0.2794)
			(end -0.12065 0.3048)
			(stroke
				(width 0.1)
				(type default)
			)
			(layer "F.Fab")
		)
		(fp_line
			(start -0.12065 0.3048)
			(end -0.67945 0.3048)
			(stroke
				(width 0.1)
				(type default)
			)
			(layer "F.Fab")
		)
		(fp_line
			(start 0.120396 0.2794)
			(end -0.12065 0.2794)
			(stroke
				(width 0.1)
				(type default)
			)
			(layer "F.Fab")
		)
		(fp_line
			(start 0.120396 0.3048)
			(end 0.120396 0.2794)
			(stroke
				(width 0.1)
				(type default)
			)
			(layer "F.Fab")
		)
		(fp_line
			(start 0.12065 -0.3048)
			(end 0.67945 -0.3048)
			(stroke
				(width 0.1)
				(type default)
			)
			(layer "F.Fab")
		)
		(fp_line
			(start 0.12065 -0.2794)
			(end 0.12065 -0.3048)
			(stroke
				(width 0.1)
				(type default)
			)
			(layer "F.Fab")
		)
		(fp_line
			(start 0.67945 -0.3048)
			(end 0.67945 0.3048)
			(stroke
				(width 0.1)
				(type default)
			)
			(layer "F.Fab")
		)
		(fp_line
			(start 0.67945 0.3048)
			(end 0.120396 0.3048)
			(stroke
				(width 0.1)
				(type default)
			)
			(layer "F.Fab")
		)
		(pad "1" smd circle
			(at -0.40005 0)
			(size 0 0)
			(layers "F.Cu" "F.Mask" "F.Paste")
			(net "SMB_ISO_SSD9_R_SDA")
		)
		(pad "2" smd circle
			(at 0.40005 0)
			(size 0 0)
			(layers "F.Cu" "F.Mask" "F.Paste")
			(net "SMB_ISO_SSD9_SDA")
		)
	)
	(footprint ""
		(layer "F.Cu")
		(at 235.882688 -175.78324 -90)
		(property "Reference" "U327"
			(at 1.74244 -2.370582 90)
			(unlocked yes)
			(layer "F.SilkS")
			(effects
				(font
					(size 0.7874 0.5842)
					(thickness 0.1524)
				)
				(justify left)
			)
		)
		(property "Value" ""
			(at 0 0 270)
			(layer "F.Fab")
			(effects
				(font
					(size 1.27 1.27)
				)
			)
		)
		(duplicate_pad_numbers_are_jumpers no)
		(fp_line
			(start -2.0574 1.651)
			(end -2.0574 -1.651)
			(stroke
				(width 0.1524)
				(type default)
			)
			(layer "F.SilkS")
		)
		(fp_line
			(start 2.0574 1.651)
			(end -2.0574 1.651)
			(stroke
				(width 0.1524)
				(type default)
			)
			(layer "F.SilkS")
		)
		(fp_line
			(start 0 -1.016)
			(end 0.381 -1.651)
			(stroke
				(width 0.1524)
				(type default)
			)
			(layer "F.SilkS")
		)
		(fp_line
			(start -2.0574 -1.651)
			(end -0.381 -1.651)
			(stroke
				(width 0.1524)
				(type default)
			)
			(layer "F.SilkS")
		)
		(fp_line
			(start -0.381 -1.651)
			(end 0 -1.016)
			(stroke
				(width 0.1524)
				(type default)
			)
			(layer "F.SilkS")
		)
		(fp_line
			(start 0.381 -1.651)
			(end 2.0574 -1.651)
			(stroke
				(width 0.1524)
				(type default)
			)
			(layer "F.SilkS")
		)
		(fp_line
			(start 2.0574 -1.651)
			(end 2.0574 1.651)
			(stroke
				(width 0.1524)
				(type default)
			)
			(layer "F.SilkS")
		)
		(fp_poly
			(pts
				(xy -2.71272 -0.719328) (xy -2.71272 -1.344168) (xy -2.159 -1.016)
			)
			(stroke
				(width 0)
				(type default)
			)
			(fill yes)
			(layer "F.SilkS")
		)
		(fp_line
			(start -0.899922 1.549908)
			(end -0.899922 1.199896)
			(stroke
				(width 0.1)
				(type default)
			)
			(layer "F.Fab")
		)
		(fp_line
			(start 0.899922 1.549908)
			(end -0.899922 1.549908)
			(stroke
				(width 0.1)
				(type default)
			)
			(layer "F.Fab")
		)
		(fp_line
			(start -1.599946 1.199896)
			(end -1.599946 -1.199896)
			(stroke
				(width 0.1)
				(type default)
			)
			(layer "F.Fab")
		)
		(fp_line
			(start -0.899922 1.199896)
			(end -1.599946 1.199896)
			(stroke
				(width 0.1)
				(type default)
			)
			(layer "F.Fab")
		)
		(fp_line
			(start 0.899922 1.199896)
			(end 0.899922 1.549908)
			(stroke
				(width 0.1)
				(type default)
			)
			(layer "F.Fab")
		)
		(fp_line
			(start 1.599946 1.199896)
			(end 0.899922 1.199896)
			(stroke
				(width 0.1)
				(type default)
			)
			(layer "F.Fab")
		)
		(fp_line
			(start -1.599946 -1.199896)
			(end -0.899922 -1.199896)
			(stroke
				(width 0.1)
				(type default)
			)
			(layer "F.Fab")
		)
		(fp_line
			(start -0.899922 -1.199896)
			(end -0.899922 -1.549908)
			(stroke
				(width 0.1)
				(type default)
			)
			(layer "F.Fab")
		)
		(fp_line
			(start 0.899922 -1.199896)
			(end 1.599946 -1.199896)
			(stroke
				(width 0.1)
				(type default)
			)
			(layer "F.Fab")
		)
		(fp_line
			(start 1.599946 -1.199896)
			(end 1.599946 1.199896)
			(stroke
				(width 0.1)
				(type default)
			)
			(layer "F.Fab")
		)
		(fp_line
			(start -0.899922 -1.549908)
			(end 0.899922 -1.549908)
			(stroke
				(width 0.1)
				(type default)
			)
			(layer "F.Fab")
		)
		(fp_line
			(start 0.899922 -1.549908)
			(end 0.899922 -1.199896)
			(stroke
				(width 0.1)
				(type default)
			)
			(layer "F.Fab")
		)
		(fp_poly
			(pts
				(xy -2.71272 -0.719328) (xy -2.71272 -1.344168) (xy -2.159 -1.016)
			)
			(stroke
				(width 0)
				(type default)
			)
			(fill yes)
			(layer "F.Fab")
		)
		(pad "1" smd rect
			(at -1.225042 -0.94996 180)
			(size 0.5588 1.3462)
			(layers "F.Cu" "F.Mask" "F.Paste")
			(net "BIC_RST_PWRGD_RSMRST")
		)
		(pad "2" smd rect
			(at -1.225042 0 180)
			(size 0.5588 1.3462)
			(layers "F.Cu" "F.Mask" "F.Paste")
			(net "RST_FPGA_BIC_R1_N")
		)
		(pad "3" smd rect
			(at -1.225042 0.94996 180)
			(size 0.5588 1.3462)
			(layers "F.Cu" "F.Mask" "F.Paste")
			(net "GND")
		)
		(pad "4" smd rect
			(at 1.225042 0.94996 180)
			(size 0.5588 1.3462)
			(layers "F.Cu" "F.Mask" "F.Paste")
			(net "RST_BIC_SRST_N")
		)
		(pad "5" smd rect
			(at 1.225042 -0.94996 180)
			(size 0.5588 1.3462)
			(layers "F.Cu" "F.Mask" "F.Paste")
			(net "P3V3_AUX")
		)
	)
	(footprint ""
		(layer "F.Cu")
		(at 249.20575 -84.320888 180)
		(property "Reference" "R1052"
			(at 0 0 180)
			(layer "F.SilkS")
			(hide yes)
			(effects
				(font
					(size 1.27 1.27)
				)
			)
		)
		(property "Value" ""
			(at 0 0 180)
			(layer "F.Fab")
			(effects
				(font
					(size 1.27 1.27)
				)
			)
		)
		(duplicate_pad_numbers_are_jumpers no)
		(fp_line
			(start 0.7874 0.4064)
			(end -0.7874 0.4064)
			(stroke
				(width 0.1524)
				(type default)
			)
			(layer "F.SilkS")
		)
		(fp_line
			(start 0.7874 -0.4064)
			(end 0.7874 0.4064)
			(stroke
				(width 0.1524)
				(type default)
			)
			(layer "F.SilkS")
		)
		(fp_line
			(start -0.7874 0.4064)
			(end -0.7874 -0.4064)
			(stroke
				(width 0.1524)
				(type default)
			)
			(layer "F.SilkS")
		)
		(fp_line
			(start -0.7874 -0.4064)
			(end 0.7874 -0.4064)
			(stroke
				(width 0.1524)
				(type default)
			)
			(layer "F.SilkS")
		)
		(fp_line
			(start 0.67945 0.3048)
			(end 0.120396 0.3048)
			(stroke
				(width 0.1)
				(type default)
			)
			(layer "F.Fab")
		)
		(fp_line
			(start 0.67945 -0.3048)
			(end 0.67945 0.3048)
			(stroke
				(width 0.1)
				(type default)
			)
			(layer "F.Fab")
		)
		(fp_line
			(start 0.12065 -0.2794)
			(end 0.12065 -0.3048)
			(stroke
				(width 0.1)
				(type default)
			)
			(layer "F.Fab")
		)
		(fp_line
			(start 0.12065 -0.3048)
			(end 0.67945 -0.3048)
			(stroke
				(width 0.1)
				(type default)
			)
			(layer "F.Fab")
		)
		(fp_line
			(start 0.120396 0.3048)
			(end 0.120396 0.2794)
			(stroke
				(width 0.1)
				(type default)
			)
			(layer "F.Fab")
		)
		(fp_line
			(start 0.120396 0.2794)
			(end -0.12065 0.2794)
			(stroke
				(width 0.1)
				(type default)
			)
			(layer "F.Fab")
		)
		(fp_line
			(start -0.12065 0.3048)
			(end -0.67945 0.3048)
			(stroke
				(width 0.1)
				(type default)
			)
			(layer "F.Fab")
		)
		(fp_line
			(start -0.12065 0.2794)
			(end -0.12065 0.3048)
			(stroke
				(width 0.1)
				(type default)
			)
			(layer "F.Fab")
		)
		(fp_line
			(start -0.12065 -0.2794)
			(end 0.12065 -0.2794)
			(stroke
				(width 0.1)
				(type default)
			)
			(layer "F.Fab")
		)
		(fp_line
			(start -0.12065 -0.305054)
			(end -0.12065 -0.2794)
			(stroke
				(width 0.1)
				(type default)
			)
			(layer "F.Fab")
		)
		(fp_line
			(start -0.67945 0.3048)
			(end -0.67945 -0.305054)
			(stroke
				(width 0.1)
				(type default)
			)
			(layer "F.Fab")
		)
		(fp_line
			(start -0.67945 -0.305054)
			(end -0.12065 -0.305054)
			(stroke
				(width 0.1)
				(type default)
			)
			(layer "F.Fab")
		)
		(pad "1" smd circle
			(at -0.40005 0 180)
			(size 0 0)
			(layers "F.Cu" "F.Mask" "F.Paste")
			(net "CLK_CK440_SMB_ADDR0")
		)
		(pad "2" smd circle
			(at 0.40005 0 180)
			(size 0 0)
			(layers "F.Cu" "F.Mask" "F.Paste")
			(net "P3V3")
		)
	)
	(footprint ""
		(layer "F.Cu")
		(at 437.250332 -343.952322 90)
		(property "Reference" "C2465"
			(at 0 0 90)
			(layer "F.SilkS")
			(hide yes)
			(effects
				(font
					(size 1.27 1.27)
				)
			)
		)
		(property "Value" ""
			(at 0 0 90)
			(layer "F.Fab")
			(effects
				(font
					(size 1.27 1.27)
				)
			)
		)
		(duplicate_pad_numbers_are_jumpers no)
		(fp_line
			(start 0.299974 -0.150114)
			(end 0.299974 0.150114)
			(stroke
				(width 0.1)
				(type default)
			)
			(layer "F.Fab")
		)
		(fp_line
			(start -0.299974 -0.150114)
			(end 0.299974 -0.150114)
			(stroke
				(width 0.1)
				(type default)
			)
			(layer "F.Fab")
		)
		(fp_line
			(start 0.299974 0.150114)
			(end -0.299974 0.150114)
			(stroke
				(width 0.1)
				(type default)
			)
			(layer "F.Fab")
		)
		(fp_line
			(start -0.299974 0.150114)
			(end -0.299974 -0.150114)
			(stroke
				(width 0.1)
				(type default)
			)
			(layer "F.Fab")
		)
		(pad "1" smd rect
			(at -0.2667 0 90)
			(size 0.3048 0.381)
			(layers "F.Cu" "F.Mask" "F.Paste")
			(net "P5E_PEX3_STN4_TX_DP<66>")
		)
		(pad "2" smd rect
			(at 0.2667 0 90)
			(size 0.3048 0.381)
			(layers "F.Cu" "F.Mask" "F.Paste")
			(net "P5E_PEX3_STN4_TX_C_DP<66>")
		)
	)
)
